(kicad_pcb
	(version 20260206)
	(generator "pcbnew")
	(generator_version "10.0")
	(general
		(thickness 1.6)
		(legacy_teardrops no)
	)
	(paper "A4")
	(title_block
		(title "peb — Lightning_PEB_BRD.brd")
		(comment 1 "Lightning (Wiwynn / Facebook NVMe JBOF) / footprints 1767-1774 of 2563")
	)
	(layers
		(0 "F.Cu" signal "TOP")
		(4 "In1.Cu" signal "L2GND")
		(6 "In2.Cu" signal "L3")
		(8 "In3.Cu" signal "L4VCC")
		(10 "In4.Cu" signal "L5VCC")
		(12 "In5.Cu" signal "L6")
		(14 "In6.Cu" signal "L7GND")
		(2 "B.Cu" signal "BOTTOM")
		(9 "F.Adhes" user "F.Adhesive")
		(11 "B.Adhes" user "B.Adhesive")
		(13 "F.Paste" user "Package Geometry/Pastemask Top")
		(15 "B.Paste" user "Package Geometry/Pastemask Bottom")
		(5 "F.SilkS" user "Ref Des/Silkscreen Top")
		(7 "B.SilkS" user "Ref Des/Silkscreen Bottom")
		(1 "F.Mask" user "Board Geometry/Soldermask Top")
		(3 "B.Mask" user "Board Geometry/Soldermask Bottom")
		(17 "Dwgs.User" user "User.Drawings")
		(19 "Cmts.User" user "User.Comments")
		(21 "Eco1.User" user "User.Eco1")
		(23 "Eco2.User" user "User.Eco2")
		(25 "Edge.Cuts" user "Board Geometry/Outline")
		(27 "Margin" user)
		(31 "F.CrtYd" user "Package Geometry/Place Bound Top")
		(29 "B.CrtYd" user "Package Geometry/Place Bound Bottom")
		(35 "F.Fab" user "Ref Des/Assembly Top")
		(33 "B.Fab" user "Ref Des/Assembly Bottom")
	)
	(footprint ""
		(layer "B.Cu")
		(at 68.834 -192.786 90)
		(property "Reference" "C8091"
			(at 0 0 90)
			(layer "B.SilkS")
			(hide yes)
			(effects
				(font
					(size 1.27 1.27)
				)
				(justify mirror)
			)
		)
		(property "Value" "SCD047U25V2KX-GP"
			(at -1.1811 -2.7051 90)
			(unlocked yes)
			(layer "B.Fab")
			(hide yes)
			(effects
				(font
					(size 1.016 1.016)
					(thickness 0.1524)
				)
				(justify mirror)
			)
		)
		(property "Device Type" "C402H22"
			(at -1.1811 -4.2291 90)
			(unlocked yes)
			(layer "B.Fab")
			(hide yes)
			(effects
				(font
					(size 1.016 1.016)
					(thickness 0.1524)
				)
				(justify mirror)
			)
		)
		(duplicate_pad_numbers_are_jumpers no)
		(fp_rect
			(start 0.4318 0.9525)
			(end -0.4318 -0.9525)
			(stroke
				(width 0)
				(type default)
			)
			(fill no)
			(layer "B.CrtYd")
		)
		(fp_rect
			(start 0.4318 0.9525)
			(end -0.4318 -0.9525)
			(stroke
				(width 0)
				(type default)
			)
			(fill no)
			(layer "B.Fab")
		)
		(pad "1" smd custom
			(at 0 -0.4445 270)
			(size 0.1524 0.1524)
			(layers "B.Cu" "B.Mask" "B.Paste")
			(net "P3V3_STBY")
			(options
				(clearance outline)
				(anchor circle)
			)
			(primitives
				(gr_poly
					(pts
						(arc
							(start 0.3048 0.2032)
							(mid 0.275042 0.275042)
							(end 0.2032 0.3048)
						)
						(arc
							(start -0.2032 0.3048)
							(mid -0.275042 0.275042)
							(end -0.3048 0.2032)
						)
						(arc
							(start -0.3048 -0.2032)
							(mid -0.275042 -0.275042)
							(end -0.2032 -0.3048)
						)
						(arc
							(start 0.2032 -0.3048)
							(mid 0.275042 -0.275042)
							(end 0.3048 -0.2032)
						)
					)
					(width 0)
					(fill yes)
				)
			)
		)
		(pad "2" smd custom
			(at 0 0.4445 270)
			(size 0.1524 0.1524)
			(layers "B.Cu" "B.Mask" "B.Paste")
			(net "GND")
			(options
				(clearance outline)
				(anchor circle)
			)
			(primitives
				(gr_poly
					(pts
						(arc
							(start 0.3048 0.2032)
							(mid 0.275042 0.275042)
							(end 0.2032 0.3048)
						)
						(arc
							(start -0.2032 0.3048)
							(mid -0.275042 0.275042)
							(end -0.3048 0.2032)
						)
						(arc
							(start -0.3048 -0.2032)
							(mid -0.275042 -0.275042)
							(end -0.2032 -0.3048)
						)
						(arc
							(start 0.2032 -0.3048)
							(mid 0.275042 -0.275042)
							(end 0.3048 -0.2032)
						)
					)
					(width 0)
					(fill yes)
				)
			)
		)
	)
	(footprint ""
		(layer "B.Cu")
		(at 219.837 -196.977)
		(property "Reference" "U67"
			(at 0 0 0)
			(layer "B.SilkS")
			(hide yes)
			(effects
				(font
					(size 1.27 1.27)
				)
				(justify mirror)
			)
		)
		(property "Value" "SN74LVC1G08DCKR-GP"
			(at 2.3368 -8.6868 0)
			(unlocked yes)
			(layer "B.Fab")
			(hide yes)
			(effects
				(font
					(size 1.016 1.016)
					(thickness 0.1524)
				)
				(justify mirror)
			)
		)
		(property "Device Type" "SC70-5H44"
			(at 2.3114 -10.414 0)
			(unlocked yes)
			(layer "B.Fab")
			(hide yes)
			(effects
				(font
					(size 1.016 1.016)
					(thickness 0.1524)
				)
				(justify mirror)
			)
		)
		(duplicate_pad_numbers_are_jumpers no)
		(fp_line
			(start -1.3843 -1.8034)
			(end -1.3843 -1.1176)
			(stroke
				(width 0.3302)
				(type default)
			)
			(layer "B.SilkS")
		)
		(fp_line
			(start -1.27 -1.7018)
			(end -1.27 1.7018)
			(stroke
				(width 0.1524)
				(type default)
			)
			(layer "B.SilkS")
		)
		(fp_line
			(start -1.27 1.7018)
			(end 1.27 1.7018)
			(stroke
				(width 0.1524)
				(type default)
			)
			(layer "B.SilkS")
		)
		(fp_line
			(start -0.6604 -1.8034)
			(end -1.3843 -1.8034)
			(stroke
				(width 0.3302)
				(type default)
			)
			(layer "B.SilkS")
		)
		(fp_line
			(start 1.27 -1.7018)
			(end -1.27 -1.7018)
			(stroke
				(width 0.1524)
				(type default)
			)
			(layer "B.SilkS")
		)
		(fp_line
			(start 1.27 1.7018)
			(end 1.27 -1.7018)
			(stroke
				(width 0.1524)
				(type default)
			)
			(layer "B.SilkS")
		)
		(fp_rect
			(start 1.524 1.9558)
			(end -1.524 -1.9558)
			(stroke
				(width 0)
				(type default)
			)
			(fill no)
			(layer "B.CrtYd")
		)
		(fp_poly
			(pts
				(xy 1.524 -1.9558) (xy -1.524 -1.9558) (xy -1.524 1.9558) (xy 1.524 1.9558)
			)
			(stroke
				(width 0)
				(type default)
			)
			(fill no)
			(layer "B.Fab")
		)
		(pad "1" smd rect
			(at -0.65024 -0.8255 180)
			(size 0.4064 1.2192)
			(layers "B.Cu" "B.Mask" "B.Paste")
			(net "BMC_SSD_RST#0_A3")
		)
		(pad "2" smd rect
			(at 0 -0.8255 180)
			(size 0.4064 1.2192)
			(layers "B.Cu" "B.Mask" "B.Paste")
			(net "SSD_PERST#0_B3")
		)
		(pad "3" smd rect
			(at 0.65024 -0.8255 180)
			(size 0.4064 1.2192)
			(layers "B.Cu" "B.Mask" "B.Paste")
			(net "GND")
		)
		(pad "4" smd rect
			(at 0.65024 0.8255 180)
			(size 0.4064 1.2192)
			(layers "B.Cu" "B.Mask" "B.Paste")
			(net "SSD_PERST_Y3")
		)
		(pad "5" smd rect
			(at -0.65024 0.8255 180)
			(size 0.4064 1.2192)
			(layers "B.Cu" "B.Mask" "B.Paste")
			(net "P3V3_STBY")
		)
	)
	(footprint ""
		(layer "B.Cu")
		(at 241.0968 -47.032672 90)
		(property "Reference" "C448"
			(at 0 0 90)
			(layer "B.SilkS")
			(hide yes)
			(effects
				(font
					(size 1.27 1.27)
				)
				(justify mirror)
			)
		)
		(property "Value" "SCD1U16V1KX-1-GP"
			(at 2.8321 -1.7399 90)
			(unlocked yes)
			(layer "B.Fab")
			(hide yes)
			(effects
				(font
					(size 1.016 1.016)
					(thickness 0.1524)
				)
				(justify mirror)
			)
		)
		(property "Device Type" "C0201H13"
			(at 2.8321 -3.2639 90)
			(unlocked yes)
			(layer "B.Fab")
			(hide yes)
			(effects
				(font
					(size 1.016 1.016)
					(thickness 0.1524)
				)
				(justify mirror)
			)
		)
		(duplicate_pad_numbers_are_jumpers no)
		(fp_rect
			(start 0.2794 0.6477)
			(end -0.2794 -0.6477)
			(stroke
				(width 0)
				(type default)
			)
			(fill no)
			(layer "B.CrtYd")
		)
		(fp_rect
			(start 0.2794 0.6477)
			(end -0.2794 -0.6477)
			(stroke
				(width 0)
				(type default)
			)
			(fill no)
			(layer "B.Fab")
		)
		(pad "1" smd custom
			(at 0 -0.2794 270)
			(size 0.0762 0.0762)
			(layers "B.Cu" "B.Mask" "B.Paste")
			(net "DUT_VDD")
			(options
				(clearance outline)
				(anchor circle)
			)
			(primitives
				(gr_poly
					(pts
						(arc
							(start 0.1524 0.127)
							(mid 0.137521 0.162921)
							(end 0.1016 0.1778)
						)
						(arc
							(start -0.1016 0.1778)
							(mid -0.137521 0.162921)
							(end -0.1524 0.127)
						)
						(arc
							(start -0.1524 -0.127)
							(mid -0.137521 -0.162921)
							(end -0.1016 -0.1778)
						)
						(arc
							(start 0.1016 -0.1778)
							(mid 0.137521 -0.162921)
							(end 0.1524 -0.127)
						)
					)
					(width 0)
					(fill yes)
				)
			)
		)
		(pad "2" smd custom
			(at 0 0.2794 270)
			(size 0.0762 0.0762)
			(layers "B.Cu" "B.Mask" "B.Paste")
			(net "GND")
			(options
				(clearance outline)
				(anchor circle)
			)
			(primitives
				(gr_poly
					(pts
						(arc
							(start 0.1524 0.127)
							(mid 0.137521 0.162921)
							(end 0.1016 0.1778)
						)
						(arc
							(start -0.1016 0.1778)
							(mid -0.137521 0.162921)
							(end -0.1524 0.127)
						)
						(arc
							(start -0.1524 -0.127)
							(mid -0.137521 -0.162921)
							(end -0.1016 -0.1778)
						)
						(arc
							(start 0.1016 -0.1778)
							(mid 0.137521 -0.162921)
							(end 0.1524 -0.127)
						)
					)
					(width 0)
					(fill yes)
				)
			)
		)
	)
	(footprint ""
		(layer "B.Cu")
		(at 171.999402 -62.714632)
		(property "Reference" "PC202"
			(at 0 0 0)
			(layer "B.SilkS")
			(hide yes)
			(effects
				(font
					(size 1.27 1.27)
				)
				(justify mirror)
			)
		)
		(property "Value" "SC22U6D3V5MX-5-GP"
			(at 0.0762 -6.1214 0)
			(unlocked yes)
			(layer "B.Fab")
			(hide yes)
			(effects
				(font
					(size 1.016 1.016)
					(thickness 0.1524)
				)
				(justify mirror)
			)
		)
		(property "Device Type" "C805H56"
			(at 0.0762 -8.1534 0)
			(unlocked yes)
			(layer "B.Fab")
			(hide yes)
			(effects
				(font
					(size 1.016 1.016)
					(thickness 0.1524)
				)
				(justify mirror)
			)
		)
		(duplicate_pad_numbers_are_jumpers no)
		(fp_line
			(start -0.635 0)
			(end 0.635 0)
			(stroke
				(width 0.508)
				(type default)
			)
			(layer "B.SilkS")
		)
		(fp_rect
			(start 0.9652 1.778)
			(end -0.9652 -1.778)
			(stroke
				(width 0)
				(type default)
			)
			(fill no)
			(layer "B.CrtYd")
		)
		(fp_poly
			(pts
				(xy 0.9652 -1.778) (xy -0.9652 -1.778) (xy -0.9652 1.778) (xy 0.9652 1.778)
			)
			(stroke
				(width 0)
				(type default)
			)
			(fill no)
			(layer "B.Fab")
		)
		(pad "1" smd rect
			(at 0 -0.9652 180)
			(size 1.397 1.143)
			(layers "B.Cu" "B.Mask" "B.Paste")
			(net "P0V9")
		)
		(pad "2" smd rect
			(at 0 0.9652 180)
			(size 1.397 1.143)
			(layers "B.Cu" "B.Mask" "B.Paste")
			(net "GND")
		)
	)
	(footprint ""
		(layer "B.Cu")
		(at 121.9708 -96.1898 180)
		(property "Reference" "R431"
			(at 0 0 0)
			(layer "B.SilkS")
			(hide yes)
			(effects
				(font
					(size 1.27 1.27)
				)
				(justify mirror)
			)
		)
		(property "Value" "0R2J-2-GP"
			(at -0.064008 -3.993896 180)
			(unlocked yes)
			(layer "B.Fab")
			(hide yes)
			(effects
				(font
					(size 1.016 1.016)
					(thickness 0.1524)
				)
				(justify mirror)
			)
		)
		(property "Device Type" "R402H16"
			(at -0.064008 -5.517896 180)
			(unlocked yes)
			(layer "B.Fab")
			(hide yes)
			(effects
				(font
					(size 1.016 1.016)
					(thickness 0.1524)
				)
				(justify mirror)
			)
		)
		(duplicate_pad_numbers_are_jumpers no)
		(fp_line
			(start 0.508 -0.9398)
			(end 0.508 0.9398)
			(stroke
				(width 0.1524)
				(type default)
			)
			(layer "B.SilkS")
		)
		(fp_line
			(start -0.508 -0.9398)
			(end 0.508 -0.9398)
			(stroke
				(width 0.1524)
				(type default)
			)
			(layer "B.SilkS")
		)
		(fp_rect
			(start 0.508 0.9398)
			(end -0.508 -0.9398)
			(stroke
				(width 0)
				(type default)
			)
			(fill no)
			(layer "B.CrtYd")
		)
		(fp_rect
			(start 0.508 0.9398)
			(end -0.508 -0.9398)
			(stroke
				(width 0)
				(type default)
			)
			(fill no)
			(layer "B.Fab")
		)
		(pad "1" smd custom
			(at 0 -0.4445)
			(size 0.1397 0.1397)
			(layers "B.Cu" "B.Mask" "B.Paste")
			(net "BMC_I2C10_8536_SCL")
			(options
				(clearance outline)
				(anchor circle)
			)
			(primitives
				(gr_poly
					(pts
						(arc
							(start -0.1778 0.2794)
							(mid -0.249642 0.249642)
							(end -0.2794 0.1778)
						)
						(arc
							(start -0.2794 -0.1778)
							(mid -0.249642 -0.249642)
							(end -0.1778 -0.2794)
						)
						(arc
							(start 0.1778 -0.2794)
							(mid 0.249642 -0.249642)
							(end 0.2794 -0.1778)
						)
						(arc
							(start 0.2794 0.1778)
							(mid 0.249642 0.249642)
							(end 0.1778 0.2794)
						)
					)
					(width 0)
					(fill yes)
				)
			)
		)
		(pad "2" smd custom
			(at 0 0.4445)
			(size 0.1397 0.1397)
			(layers "B.Cu" "B.Mask" "B.Paste")
			(net "TWI_SCL0")
			(options
				(clearance outline)
				(anchor circle)
			)
			(primitives
				(gr_poly
					(pts
						(arc
							(start -0.1778 0.2794)
							(mid -0.249642 0.249642)
							(end -0.2794 0.1778)
						)
						(arc
							(start -0.2794 -0.1778)
							(mid -0.249642 -0.249642)
							(end -0.1778 -0.2794)
						)
						(arc
							(start 0.1778 -0.2794)
							(mid 0.249642 -0.249642)
							(end 0.2794 -0.1778)
						)
						(arc
							(start 0.2794 0.1778)
							(mid 0.249642 0.249642)
							(end 0.1778 0.2794)
						)
					)
					(width 0)
					(fill yes)
				)
			)
		)
	)
	(footprint ""
		(layer "B.Cu")
		(at 75.987656 -195.730114 180)
		(property "Reference" "R4115"
			(at 0 0 0)
			(layer "B.SilkS")
			(hide yes)
			(effects
				(font
					(size 1.27 1.27)
				)
				(justify mirror)
			)
		)
		(property "Value" "4K7R2F-GP"
			(at -0.064008 -3.993896 180)
			(unlocked yes)
			(layer "B.Fab")
			(hide yes)
			(effects
				(font
					(size 1.016 1.016)
					(thickness 0.1524)
				)
				(justify mirror)
			)
		)
		(property "Device Type" "R402H16"
			(at -0.064008 -5.517896 180)
			(unlocked yes)
			(layer "B.Fab")
			(hide yes)
			(effects
				(font
					(size 1.016 1.016)
					(thickness 0.1524)
				)
				(justify mirror)
			)
		)
		(duplicate_pad_numbers_are_jumpers no)
		(fp_line
			(start 0.508 -0.9398)
			(end 0.508 0.9398)
			(stroke
				(width 0.1524)
				(type default)
			)
			(layer "B.SilkS")
		)
		(fp_line
			(start -0.508 -0.9398)
			(end 0.508 -0.9398)
			(stroke
				(width 0.1524)
				(type default)
			)
			(layer "B.SilkS")
		)
		(fp_rect
			(start 0.508 0.9398)
			(end -0.508 -0.9398)
			(stroke
				(width 0)
				(type default)
			)
			(fill no)
			(layer "B.CrtYd")
		)
		(fp_rect
			(start 0.508 0.9398)
			(end -0.508 -0.9398)
			(stroke
				(width 0)
				(type default)
			)
			(fill no)
			(layer "B.Fab")
		)
		(pad "1" smd custom
			(at 0 -0.4445)
			(size 0.1397 0.1397)
			(layers "B.Cu" "B.Mask" "B.Paste")
			(net "SSD_PRSNT#11")
			(options
				(clearance outline)
				(anchor circle)
			)
			(primitives
				(gr_poly
					(pts
						(arc
							(start -0.1778 0.2794)
							(mid -0.249642 0.249642)
							(end -0.2794 0.1778)
						)
						(arc
							(start -0.2794 -0.1778)
							(mid -0.249642 -0.249642)
							(end -0.1778 -0.2794)
						)
						(arc
							(start 0.1778 -0.2794)
							(mid 0.249642 -0.249642)
							(end 0.2794 -0.1778)
						)
						(arc
							(start 0.2794 0.1778)
							(mid 0.249642 0.249642)
							(end 0.1778 0.2794)
						)
					)
					(width 0)
					(fill yes)
				)
			)
		)
		(pad "2" smd custom
			(at 0 0.4445)
			(size 0.1397 0.1397)
			(layers "B.Cu" "B.Mask" "B.Paste")
			(net "P3V3_STBY")
			(options
				(clearance outline)
				(anchor circle)
			)
			(primitives
				(gr_poly
					(pts
						(arc
							(start -0.1778 0.2794)
							(mid -0.249642 0.249642)
							(end -0.2794 0.1778)
						)
						(arc
							(start -0.2794 -0.1778)
							(mid -0.249642 -0.249642)
							(end -0.1778 -0.2794)
						)
						(arc
							(start 0.1778 -0.2794)
							(mid 0.249642 -0.249642)
							(end 0.2794 -0.1778)
						)
						(arc
							(start 0.2794 0.1778)
							(mid 0.249642 0.249642)
							(end 0.1778 0.2794)
						)
					)
					(width 0)
					(fill yes)
				)
			)
		)
	)
	(footprint ""
		(layer "B.Cu")
		(at 71.724012 -195.689474)
		(property "Reference" "R519"
			(at 0 0 0)
			(layer "B.SilkS")
			(hide yes)
			(effects
				(font
					(size 1.27 1.27)
				)
				(justify mirror)
			)
		)
		(property "Value" "10KR2F-2-GP"
			(at -0.064008 -3.993896 0)
			(unlocked yes)
			(layer "B.Fab")
			(hide yes)
			(effects
				(font
					(size 1.016 1.016)
					(thickness 0.1524)
				)
				(justify mirror)
			)
		)
		(property "Device Type" "R402H16"
			(at -0.064008 -5.517896 0)
			(unlocked yes)
			(layer "B.Fab")
			(hide yes)
			(effects
				(font
					(size 1.016 1.016)
					(thickness 0.1524)
				)
				(justify mirror)
			)
		)
		(duplicate_pad_numbers_are_jumpers no)
		(fp_line
			(start -0.508 -0.9398)
			(end 0.508 -0.9398)
			(stroke
				(width 0.1524)
				(type default)
			)
			(layer "B.SilkS")
		)
		(fp_line
			(start 0.508 -0.9398)
			(end 0.508 0.9398)
			(stroke
				(width 0.1524)
				(type default)
			)
			(layer "B.SilkS")
		)
		(fp_rect
			(start 0.508 0.9398)
			(end -0.508 -0.9398)
			(stroke
				(width 0)
				(type default)
			)
			(fill no)
			(layer "B.CrtYd")
		)
		(fp_rect
			(start 0.508 0.9398)
			(end -0.508 -0.9398)
			(stroke
				(width 0)
				(type default)
			)
			(fill no)
			(layer "B.Fab")
		)
		(pad "1" smd custom
			(at 0 -0.4445 180)
			(size 0.1397 0.1397)
			(layers "B.Cu" "B.Mask" "B.Paste")
			(net "P3V3_STBY")
			(options
				(clearance outline)
				(anchor circle)
			)
			(primitives
				(gr_poly
					(pts
						(arc
							(start -0.1778 0.2794)
							(mid -0.249642 0.249642)
							(end -0.2794 0.1778)
						)
						(arc
							(start -0.2794 -0.1778)
							(mid -0.249642 -0.249642)
							(end -0.1778 -0.2794)
						)
						(arc
							(start 0.1778 -0.2794)
							(mid 0.249642 -0.249642)
							(end 0.2794 -0.1778)
						)
						(arc
							(start 0.2794 0.1778)
							(mid 0.249642 0.249642)
							(end 0.1778 0.2794)
						)
					)
					(width 0)
					(fill yes)
				)
			)
		)
		(pad "2" smd custom
			(at 0 0.4445 180)
			(size 0.1397 0.1397)
			(layers "B.Cu" "B.Mask" "B.Paste")
			(net "IOEXP1_AD0")
			(options
				(clearance outline)
				(anchor circle)
			)
			(primitives
				(gr_poly
					(pts
						(arc
							(start -0.1778 0.2794)
							(mid -0.249642 0.249642)
							(end -0.2794 0.1778)
						)
						(arc
							(start -0.2794 -0.1778)
							(mid -0.249642 -0.249642)
							(end -0.1778 -0.2794)
						)
						(arc
							(start 0.1778 -0.2794)
							(mid 0.249642 -0.249642)
							(end 0.2794 -0.1778)
						)
						(arc
							(start 0.2794 0.1778)
							(mid 0.249642 0.249642)
							(end 0.1778 0.2794)
						)
					)
					(width 0)
					(fill yes)
				)
			)
		)
	)
	(footprint ""
		(layer "B.Cu")
		(at 48.641 -148.082 180)
		(property "Reference" "R155"
			(at 0 0 0)
			(layer "B.SilkS")
			(hide yes)
			(effects
				(font
					(size 1.27 1.27)
				)
				(justify mirror)
			)
		)
		(property "Value" "4K7R2F-GP"
			(at -0.064008 -3.993896 180)
			(unlocked yes)
			(layer "B.Fab")
			(hide yes)
			(effects
				(font
					(size 1.016 1.016)
					(thickness 0.1524)
				)
				(justify mirror)
			)
		)
		(property "Device Type" "R402H16"
			(at -0.064008 -5.517896 180)
			(unlocked yes)
			(layer "B.Fab")
			(hide yes)
			(effects
				(font
					(size 1.016 1.016)
					(thickness 0.1524)
				)
				(justify mirror)
			)
		)
		(duplicate_pad_numbers_are_jumpers no)
		(fp_line
			(start 0.508 -0.9398)
			(end 0.508 0.9398)
			(stroke
				(width 0.1524)
				(type default)
			)
			(layer "B.SilkS")
		)
		(fp_line
			(start -0.508 -0.9398)
			(end 0.508 -0.9398)
			(stroke
				(width 0.1524)
				(type default)
			)
			(layer "B.SilkS")
		)
		(fp_rect
			(start 0.508 0.9398)
			(end -0.508 -0.9398)
			(stroke
				(width 0)
				(type default)
			)
			(fill no)
			(layer "B.CrtYd")
		)
		(fp_rect
			(start 0.508 0.9398)
			(end -0.508 -0.9398)
			(stroke
				(width 0)
				(type default)
			)
			(fill no)
			(layer "B.Fab")
		)
		(pad "1" smd custom
			(at 0 -0.4445)
			(size 0.1397 0.1397)
			(layers "B.Cu" "B.Mask" "B.Paste")
			(net "CBL_PRSNT_N_8")
			(options
				(clearance outline)
				(anchor circle)
			)
			(primitives
				(gr_poly
					(pts
						(arc
							(start -0.1778 0.2794)
							(mid -0.249642 0.249642)
							(end -0.2794 0.1778)
						)
						(arc
							(start -0.2794 -0.1778)
							(mid -0.249642 -0.249642)
							(end -0.1778 -0.2794)
						)
						(arc
							(start 0.1778 -0.2794)
							(mid 0.249642 -0.249642)
							(end 0.2794 -0.1778)
						)
						(arc
							(start 0.2794 0.1778)
							(mid 0.249642 0.249642)
							(end 0.1778 0.2794)
						)
					)
					(width 0)
					(fill yes)
				)
			)
		)
		(pad "2" smd custom
			(at 0 0.4445)
			(size 0.1397 0.1397)
			(layers "B.Cu" "B.Mask" "B.Paste")
			(net "P3V3_STBY")
			(options
				(clearance outline)
				(anchor circle)
			)
			(primitives
				(gr_poly
					(pts
						(arc
							(start -0.1778 0.2794)
							(mid -0.249642 0.249642)
							(end -0.2794 0.1778)
						)
						(arc
							(start -0.2794 -0.1778)
							(mid -0.249642 -0.249642)
							(end -0.1778 -0.2794)
						)
						(arc
							(start 0.1778 -0.2794)
							(mid 0.249642 -0.249642)
							(end 0.2794 -0.1778)
						)
						(arc
							(start 0.2794 0.1778)
							(mid 0.249642 0.249642)
							(end 0.1778 0.2794)
						)
					)
					(width 0)
					(fill yes)
				)
			)
		)
	)
)
